(kicad_pcb
	(version 20260206)
	(generator "pcbnew")
	(generator_version "10.0")
	(general
		(thickness 1.6)
		(legacy_teardrops no)
	)
	(paper "A4")
	(title_block
		(title "Wiwynn_Tioga_Pass_MB.brd")
		(comment 1 "Tioga Pass / footprints 3880-3886 of 4770")
	)
	(layers
		(0 "F.Cu" signal "TOP")
		(4 "In1.Cu" signal "L2GND")
		(6 "In2.Cu" signal "L3")
		(8 "In3.Cu" signal "L4GND")
		(10 "In4.Cu" signal "L5")
		(12 "In5.Cu" signal "L6GND")
		(14 "In6.Cu" signal "L7VCC")
		(16 "In7.Cu" signal "L8VCC")
		(18 "In8.Cu" signal "L9GND")
		(20 "In9.Cu" signal "L10")
		(22 "In10.Cu" signal "L11GND")
		(24 "In11.Cu" signal "L12")
		(26 "In12.Cu" signal "L13GND")
		(2 "B.Cu" signal "BOTTOM")
		(9 "F.Adhes" user "F.Adhesive")
		(11 "B.Adhes" user "B.Adhesive")
		(13 "F.Paste" user "Package Geometry/Pastemask Top")
		(15 "B.Paste" user "Package Geometry/Pastemask Bottom")
		(5 "F.SilkS" user "Ref Des/Silkscreen Top")
		(7 "B.SilkS" user "Ref Des/Silkscreen Bottom")
		(1 "F.Mask" user "Board Geometry/Soldermask Top")
		(3 "B.Mask" user "Board Geometry/Soldermask Bottom")
		(17 "Dwgs.User" user "User.Drawings")
		(19 "Cmts.User" user "User.Comments")
		(21 "Eco1.User" user "User.Eco1")
		(23 "Eco2.User" user "User.Eco2")
		(25 "Edge.Cuts" user "Board Geometry/Outline")
		(27 "Margin" user)
		(31 "F.CrtYd" user "Package Geometry/Place Bound Top")
		(29 "B.CrtYd" user "Package Geometry/Place Bound Bottom")
		(35 "F.Fab" user "Ref Des/Assembly Top")
		(33 "B.Fab" user "Ref Des/Assembly Bottom")
	)
	(footprint ""
		(layer "B.Cu")
		(at 394.251434 -33.139634)
		(property "Reference" "R25W181"
			(at 0.8382 -0.67818 0)
			(unlocked yes)
			(layer "B.SilkS")
			(effects
				(font
					(size 0.4064 0.254)
					(thickness 0.1524)
				)
				(justify left mirror)
			)
		)
		(property "Value" ""
			(at 0 0 0)
			(layer "B.Fab")
			(effects
				(font
					(size 1.27 1.27)
				)
				(justify mirror)
			)
		)
		(duplicate_pad_numbers_are_jumpers no)
		(fp_poly
			(pts
				(xy 0.2794 -0.1016) (xy -0.2794 -0.1016) (xy -0.2794 0.9906) (xy 0.2794 0.9906)
			)
			(stroke
				(width 0)
				(type default)
			)
			(fill no)
			(layer "B.CrtYd")
		)
		(fp_line
			(start -0.2794 -0.1016)
			(end 0.2794 -0.1016)
			(stroke
				(width 0.1)
				(type default)
			)
			(layer "B.Fab")
		)
		(fp_line
			(start -0.2794 0.9906)
			(end -0.2794 -0.1016)
			(stroke
				(width 0.1)
				(type default)
			)
			(layer "B.Fab")
		)
		(fp_line
			(start 0.2794 -0.1016)
			(end 0.2794 0.9906)
			(stroke
				(width 0.1)
				(type default)
			)
			(layer "B.Fab")
		)
		(fp_line
			(start 0.2794 0.9906)
			(end -0.2794 0.9906)
			(stroke
				(width 0.1)
				(type default)
			)
			(layer "B.Fab")
		)
		(pad "1" smd rect
			(at 0 0 180)
			(size 0.508 0.508)
			(layers "B.Cu" "B.Mask" "B.Paste")
			(net "RST_RSMRST_N")
		)
		(pad "2" smd rect
			(at 0 0.889 180)
			(size 0.508 0.508)
			(layers "B.Cu" "B.Mask" "B.Paste")
			(net "BMC_RSMRST_B_N")
		)
		(zone
			(layer "B.Cu")
			(hatch none 0.5)
			(connect_pads
				(clearance 0)
			)
			(min_thickness 0.25)
			(keepout
				(tracks allowed)
				(vias not_allowed)
				(pads allowed)
				(copperpour not_allowed)
				(footprints allowed)
			)
			(placement
				(enabled no)
				(sheetname "")
			)
			(fill
				(thermal_gap 0.5)
				(thermal_bridge_width 0.5)
				(island_removal_mode 0)
			)
			(polygon
				(pts
					(xy 394.505434 -32.885634) (xy 393.997434 -32.885634) (xy 393.997434 -32.504634) (xy 394.505434 -32.504634)
				)
			)
		)
		(zone
			(layer "B.Cu")
			(hatch none 0.5)
			(connect_pads
				(clearance 0)
			)
			(min_thickness 0.25)
			(keepout
				(tracks not_allowed)
				(vias allowed)
				(pads allowed)
				(copperpour not_allowed)
				(footprints allowed)
			)
			(placement
				(enabled no)
				(sheetname "")
			)
			(fill
				(thermal_gap 0.5)
				(thermal_bridge_width 0.5)
				(island_removal_mode 0)
			)
			(polygon
				(pts
					(xy 394.505434 -32.504634) (xy 393.997434 -32.504634) (xy 393.997434 -32.885634) (xy 394.505434 -32.885634)
				)
			)
		)
	)
	(footprint ""
		(layer "B.Cu")
		(at 404.3172 -148.082 -90)
		(property "Reference" "R2L20"
			(at 0 0 90)
			(layer "B.SilkS")
			(hide yes)
			(effects
				(font
					(size 1.27 1.27)
				)
				(justify mirror)
			)
		)
		(property "Value" ""
			(at 0 0 90)
			(layer "B.Fab")
			(effects
				(font
					(size 1.27 1.27)
				)
				(justify mirror)
			)
		)
		(duplicate_pad_numbers_are_jumpers no)
		(fp_poly
			(pts
				(xy 0.2794 -0.1016) (xy -0.2794 -0.1016) (xy -0.2794 0.9906) (xy 0.2794 0.9906)
			)
			(stroke
				(width 0)
				(type default)
			)
			(fill no)
			(layer "B.CrtYd")
		)
		(fp_line
			(start -0.2794 0.9906)
			(end -0.2794 -0.1016)
			(stroke
				(width 0.1)
				(type default)
			)
			(layer "B.Fab")
		)
		(fp_line
			(start 0.2794 0.9906)
			(end -0.2794 0.9906)
			(stroke
				(width 0.1)
				(type default)
			)
			(layer "B.Fab")
		)
		(fp_line
			(start -0.2794 -0.1016)
			(end 0.2794 -0.1016)
			(stroke
				(width 0.1)
				(type default)
			)
			(layer "B.Fab")
		)
		(fp_line
			(start 0.2794 -0.1016)
			(end 0.2794 0.9906)
			(stroke
				(width 0.1)
				(type default)
			)
			(layer "B.Fab")
		)
		(pad "1" smd rect
			(at 0 0 90)
			(size 0.508 0.508)
			(layers "B.Cu" "B.Mask" "B.Paste")
			(net "P1V8_PCH_STBY")
		)
		(pad "2" smd rect
			(at 0 0.889 90)
			(size 0.508 0.508)
			(layers "B.Cu" "B.Mask" "B.Paste")
			(net "VR_P1V8_PCH_STBY_FB")
		)
		(zone
			(layer "B.Cu")
			(hatch none 0.5)
			(connect_pads
				(clearance 0)
			)
			(min_thickness 0.25)
			(keepout
				(tracks not_allowed)
				(vias allowed)
				(pads allowed)
				(copperpour not_allowed)
				(footprints allowed)
			)
			(placement
				(enabled no)
				(sheetname "")
			)
			(fill
				(thermal_gap 0.5)
				(thermal_bridge_width 0.5)
				(island_removal_mode 0)
			)
			(polygon
				(pts
					(xy 403.6822 -147.828) (xy 403.6822 -148.336) (xy 404.0632 -148.336) (xy 404.0632 -147.828)
				)
			)
		)
		(zone
			(layer "B.Cu")
			(hatch none 0.5)
			(connect_pads
				(clearance 0)
			)
			(min_thickness 0.25)
			(keepout
				(tracks allowed)
				(vias not_allowed)
				(pads allowed)
				(copperpour not_allowed)
				(footprints allowed)
			)
			(placement
				(enabled no)
				(sheetname "")
			)
			(fill
				(thermal_gap 0.5)
				(thermal_bridge_width 0.5)
				(island_removal_mode 0)
			)
			(polygon
				(pts
					(xy 404.0632 -147.828) (xy 404.0632 -148.336) (xy 403.6822 -148.336) (xy 403.6822 -147.828)
				)
			)
		)
	)
	(footprint ""
		(layer "B.Cu")
		(at -2.59842 -18.11782 -90)
		(property "Reference" "C1G7"
			(at 0 0 90)
			(layer "B.SilkS")
			(hide yes)
			(effects
				(font
					(size 1.27 1.27)
				)
				(justify mirror)
			)
		)
		(property "Value" "*"
			(at 2.3114 0.10795 270)
			(unlocked yes)
			(layer "B.Fab")
			(hide yes)
			(effects
				(font
					(size 0.889 0.889)
					(thickness 0.1524)
				)
				(justify mirror)
			)
		)
		(property "Device Type" "ST270U2D5VBM-GP_SMD-TCG2-ST270A"
			(at 2.3114 -1.41605 270)
			(unlocked yes)
			(layer "B.Fab")
			(hide yes)
			(effects
				(font
					(size 0.889 0.889)
					(thickness 0.1524)
				)
				(justify mirror)
			)
		)
		(duplicate_pad_numbers_are_jumpers no)
		(fp_line
			(start 1.5494 0.4826)
			(end 1.5494 -0.4826)
			(stroke
				(width 0.1524)
				(type default)
			)
			(layer "B.SilkS")
		)
		(fp_line
			(start -1.5494 -0.4826)
			(end -1.5494 0.4826)
			(stroke
				(width 0.1524)
				(type default)
			)
			(layer "B.SilkS")
		)
		(fp_line
			(start 1.0922 -2.35458)
			(end -1.0922 -2.35458)
			(stroke
				(width 0.508)
				(type default)
			)
			(layer "B.SilkS")
		)
		(fp_poly
			(pts
				(xy 1.3462 1.9558) (xy 1.3462 1.905) (xy 1.5494 1.905) (xy 1.5494 -1.905) (xy 1.3462 -1.905) (xy 1.3462 -1.9558)
				(xy -1.3462 -1.9558) (xy -1.3462 -1.905) (xy -1.5494 -1.905) (xy -1.5494 1.905) (xy -1.3462 1.905)
				(xy -1.3462 1.9558)
			)
			(stroke
				(width 0)
				(type default)
			)
			(fill no)
			(layer "B.CrtYd")
		)
		(fp_poly
			(pts
				(xy 1.3462 1.9558) (xy 1.3462 1.905) (xy 1.5494 1.905) (xy 1.5494 -1.905) (xy 1.3462 -1.905) (xy 1.3462 -1.9558)
				(xy -1.3462 -1.9558) (xy -1.3462 -1.905) (xy -1.5494 -1.905) (xy -1.5494 1.905) (xy -1.3462 1.905)
				(xy -1.3462 1.9558)
			)
			(stroke
				(width 0)
				(type default)
			)
			(fill no)
			(layer "B.Fab")
		)
		(pad "1" smd rect
			(at 0 -1.27508 90)
			(size 2.6924 1.3462)
			(layers "B.Cu" "B.Mask" "B.Paste")
			(net "VR_FET_SW_P12V_STBY_PVDDQ_GHJ")
		)
		(pad "2" smd rect
			(at 0 1.27508 90)
			(size 2.6924 1.3462)
			(layers "B.Cu" "B.Mask" "B.Paste")
			(net "GND")
		)
	)
	(footprint ""
		(layer "B.Cu")
		(at 359.8164 -134.112)
		(property "Reference" "R3M3"
			(at 0 0 0)
			(layer "B.SilkS")
			(hide yes)
			(effects
				(font
					(size 1.27 1.27)
				)
				(justify mirror)
			)
		)
		(property "Value" ""
			(at 0 0 0)
			(layer "B.Fab")
			(effects
				(font
					(size 1.27 1.27)
				)
				(justify mirror)
			)
		)
		(duplicate_pad_numbers_are_jumpers no)
		(fp_rect
			(start 0.2794 0.9906)
			(end -0.2794 -0.1016)
			(stroke
				(width 0)
				(type default)
			)
			(fill no)
			(layer "B.CrtYd")
		)
		(fp_line
			(start -0.2794 -0.1016)
			(end 0.2794 -0.1016)
			(stroke
				(width 0.1)
				(type default)
			)
			(layer "B.Fab")
		)
		(fp_line
			(start -0.2794 0.9906)
			(end -0.2794 -0.1016)
			(stroke
				(width 0.1)
				(type default)
			)
			(layer "B.Fab")
		)
		(fp_line
			(start 0.2794 -0.1016)
			(end 0.2794 0.9906)
			(stroke
				(width 0.1)
				(type default)
			)
			(layer "B.Fab")
		)
		(fp_line
			(start 0.2794 0.9906)
			(end -0.2794 0.9906)
			(stroke
				(width 0.1)
				(type default)
			)
			(layer "B.Fab")
		)
		(pad "1" smd rect
			(at 0 0 180)
			(size 0.508 0.508)
			(layers "B.Cu" "B.Mask" "B.Paste")
			(net "PWRGD_PVDDQ_DEF_R")
		)
		(pad "2" smd rect
			(at 0 0.889 180)
			(size 0.508 0.508)
			(layers "B.Cu" "B.Mask" "B.Paste")
			(net "PWRGD_PVDDQ_DEF")
		)
		(zone
			(layer "B.Cu")
			(hatch none 0.5)
			(connect_pads
				(clearance 0)
			)
			(min_thickness 0.25)
			(keepout
				(tracks not_allowed)
				(vias allowed)
				(pads allowed)
				(copperpour not_allowed)
				(footprints allowed)
			)
			(placement
				(enabled no)
				(sheetname "")
			)
			(fill
				(thermal_gap 0.5)
				(thermal_bridge_width 0.5)
				(island_removal_mode 0)
			)
			(polygon
				(pts
					(xy 360.0704 -133.477) (xy 360.0704 -133.858) (xy 359.5624 -133.858) (xy 359.5624 -133.477)
				)
			)
		)
		(zone
			(layer "B.Cu")
			(hatch none 0.5)
			(connect_pads
				(clearance 0)
			)
			(min_thickness 0.25)
			(keepout
				(tracks allowed)
				(vias not_allowed)
				(pads allowed)
				(copperpour not_allowed)
				(footprints allowed)
			)
			(placement
				(enabled no)
				(sheetname "")
			)
			(fill
				(thermal_gap 0.5)
				(thermal_bridge_width 0.5)
				(island_removal_mode 0)
			)
			(polygon
				(pts
					(xy 360.0704 -133.477) (xy 360.0704 -133.858) (xy 359.5624 -133.858) (xy 359.5624 -133.477)
				)
			)
		)
	)
	(footprint ""
		(layer "B.Cu")
		(at 385.3688 -3.0988)
		(property "Reference" "U8W2"
			(at 0 -1.2065 0)
			(unlocked yes)
			(layer "B.SilkS")
			(effects
				(font
					(size 1.27 0.9652)
					(thickness 0.1524)
				)
				(justify left mirror)
			)
		)
		(property "Value" ""
			(at 0 0 0)
			(layer "B.Fab")
			(effects
				(font
					(size 1.27 1.27)
				)
				(justify mirror)
			)
		)
		(duplicate_pad_numbers_are_jumpers no)
		(fp_circle
			(center 0.848614 -0.6477)
			(end 0.975614 -0.6477)
			(stroke
				(width 0.254)
				(type default)
			)
			(fill no)
			(layer "B.SilkS")
		)
		(fp_poly
			(pts
				(xy -0.21463 -0.450088) (xy -1.56337 -0.450088) (xy -1.56337 1.75006) (xy -0.21463 1.75006)
			)
			(stroke
				(width 0)
				(type default)
			)
			(fill no)
			(layer "B.CrtYd")
		)
		(fp_line
			(start -1.56337 -0.450088)
			(end -1.56337 1.75006)
			(stroke
				(width 0.1)
				(type default)
			)
			(layer "B.Fab")
		)
		(fp_line
			(start -1.56337 1.75006)
			(end -0.21463 1.75006)
			(stroke
				(width 0.1)
				(type default)
			)
			(layer "B.Fab")
		)
		(fp_line
			(start -0.21463 -0.450088)
			(end -1.56337 -0.450088)
			(stroke
				(width 0.1)
				(type default)
			)
			(layer "B.Fab")
		)
		(fp_line
			(start -0.21463 1.75006)
			(end -0.21463 -0.450088)
			(stroke
				(width 0.1)
				(type default)
			)
			(layer "B.Fab")
		)
		(fp_circle
			(center 0.848614 -0.6477)
			(end 0.975614 -0.6477)
			(stroke
				(width 0.254)
				(type default)
			)
			(fill no)
			(layer "B.Fab")
		)
		(pad "1" smd rect
			(at 0 0 180)
			(size 1.016 0.381)
			(layers "B.Cu" "B.Mask" "B.Paste")
			(net "JTAG_PLD_TDO")
		)
		(pad "2" smd rect
			(at 0 0.649986 180)
			(size 1.016 0.381)
			(layers "B.Cu" "B.Mask" "B.Paste")
			(net "GND")
		)
		(pad "3" smd rect
			(at 0 1.299972 180)
			(size 1.016 0.381)
			(layers "B.Cu" "B.Mask" "B.Paste")
			(net "JTAG_RISER_TDO_R")
		)
		(pad "4" smd rect
			(at -1.778 1.299972 180)
			(size 1.016 0.381)
			(layers "B.Cu" "B.Mask" "B.Paste")
			(net "JTAG_PLD_TDO_MUX_R")
		)
		(pad "5" smd rect
			(at -1.778 0.649986 180)
			(size 1.016 0.381)
			(layers "B.Cu" "B.Mask" "B.Paste")
			(net "P3V3_STBY")
		)
		(pad "6" smd rect
			(at -1.778 0 180)
			(size 1.016 0.381)
			(layers "B.Cu" "B.Mask" "B.Paste")
			(net "JTAG_RISER_N")
		)
	)
	(footprint ""
		(layer "B.Cu")
		(at 482.65969 -57.307988 -90)
		(property "Reference" "R8E27"
			(at 0 0 90)
			(layer "B.SilkS")
			(hide yes)
			(effects
				(font
					(size 1.27 1.27)
				)
				(justify mirror)
			)
		)
		(property "Value" ""
			(at 0 0 90)
			(layer "B.Fab")
			(effects
				(font
					(size 1.27 1.27)
				)
				(justify mirror)
			)
		)
		(duplicate_pad_numbers_are_jumpers no)
		(fp_poly
			(pts
				(xy 0.2794 -0.1016) (xy -0.2794 -0.1016) (xy -0.2794 0.9906) (xy 0.2794 0.9906)
			)
			(stroke
				(width 0)
				(type default)
			)
			(fill no)
			(layer "B.CrtYd")
		)
		(fp_line
			(start -0.2794 0.9906)
			(end -0.2794 -0.1016)
			(stroke
				(width 0.1)
				(type default)
			)
			(layer "B.Fab")
		)
		(fp_line
			(start 0.2794 0.9906)
			(end -0.2794 0.9906)
			(stroke
				(width 0.1)
				(type default)
			)
			(layer "B.Fab")
		)
		(fp_line
			(start -0.2794 -0.1016)
			(end 0.2794 -0.1016)
			(stroke
				(width 0.1)
				(type default)
			)
			(layer "B.Fab")
		)
		(fp_line
			(start 0.2794 -0.1016)
			(end 0.2794 0.9906)
			(stroke
				(width 0.1)
				(type default)
			)
			(layer "B.Fab")
		)
		(pad "1" smd rect
			(at 0 0 90)
			(size 0.508 0.508)
			(layers "B.Cu" "B.Mask" "B.Paste")
			(net "FM_PE_M2_WAKE_N")
		)
		(pad "2" smd rect
			(at 0 0.889 90)
			(size 0.508 0.508)
			(layers "B.Cu" "B.Mask" "B.Paste")
			(net "FM_ALL_WAKE_N")
		)
		(zone
			(layer "B.Cu")
			(hatch none 0.5)
			(connect_pads
				(clearance 0)
			)
			(min_thickness 0.25)
			(keepout
				(tracks not_allowed)
				(vias allowed)
				(pads allowed)
				(copperpour not_allowed)
				(footprints allowed)
			)
			(placement
				(enabled no)
				(sheetname "")
			)
			(fill
				(thermal_gap 0.5)
				(thermal_bridge_width 0.5)
				(island_removal_mode 0)
			)
			(polygon
				(pts
					(xy 482.02469 -57.053988) (xy 482.02469 -57.561988) (xy 482.40569 -57.561988) (xy 482.40569 -57.053988)
				)
			)
		)
		(zone
			(layer "B.Cu")
			(hatch none 0.5)
			(connect_pads
				(clearance 0)
			)
			(min_thickness 0.25)
			(keepout
				(tracks allowed)
				(vias not_allowed)
				(pads allowed)
				(copperpour not_allowed)
				(footprints allowed)
			)
			(placement
				(enabled no)
				(sheetname "")
			)
			(fill
				(thermal_gap 0.5)
				(thermal_bridge_width 0.5)
				(island_removal_mode 0)
			)
			(polygon
				(pts
					(xy 482.40569 -57.053988) (xy 482.40569 -57.561988) (xy 482.02469 -57.561988) (xy 482.02469 -57.053988)
				)
			)
		)
	)
	(footprint ""
		(layer "B.Cu")
		(at 433.578 -153.543 -90)
		(property "Reference" "R2L11"
			(at 0 0 90)
			(layer "B.SilkS")
			(hide yes)
			(effects
				(font
					(size 1.27 1.27)
				)
				(justify mirror)
			)
		)
		(property "Value" ""
			(at 0 0 90)
			(layer "B.Fab")
			(effects
				(font
					(size 1.27 1.27)
				)
				(justify mirror)
			)
		)
		(duplicate_pad_numbers_are_jumpers no)
		(fp_poly
			(pts
				(xy 0.2794 -0.1016) (xy -0.2794 -0.1016) (xy -0.2794 0.9906) (xy 0.2794 0.9906)
			)
			(stroke
				(width 0)
				(type default)
			)
			(fill no)
			(layer "B.CrtYd")
		)
		(fp_line
			(start -0.2794 0.9906)
			(end -0.2794 -0.1016)
			(stroke
				(width 0.1)
				(type default)
			)
			(layer "B.Fab")
		)
		(fp_line
			(start 0.2794 0.9906)
			(end -0.2794 0.9906)
			(stroke
				(width 0.1)
				(type default)
			)
			(layer "B.Fab")
		)
		(fp_line
			(start -0.2794 -0.1016)
			(end 0.2794 -0.1016)
			(stroke
				(width 0.1)
				(type default)
			)
			(layer "B.Fab")
		)
		(fp_line
			(start 0.2794 -0.1016)
			(end 0.2794 0.9906)
			(stroke
				(width 0.1)
				(type default)
			)
			(layer "B.Fab")
		)
		(pad "1" smd rect
			(at 0 0 90)
			(size 0.508 0.508)
			(layers "B.Cu" "B.Mask" "B.Paste")
			(net "P3V3_STBY")
		)
		(pad "2" smd rect
			(at 0 0.889 90)
			(size 0.508 0.508)
			(layers "B.Cu" "B.Mask" "B.Paste")
			(net "SGPIO_PCH_SATA_CLOCK_R")
		)
		(zone
			(layer "B.Cu")
			(hatch none 0.5)
			(connect_pads
				(clearance 0)
			)
			(min_thickness 0.25)
			(keepout
				(tracks not_allowed)
				(vias allowed)
				(pads allowed)
				(copperpour not_allowed)
				(footprints allowed)
			)
			(placement
				(enabled no)
				(sheetname "")
			)
			(fill
				(thermal_gap 0.5)
				(thermal_bridge_width 0.5)
				(island_removal_mode 0)
			)
			(polygon
				(pts
					(xy 432.943 -153.289) (xy 432.943 -153.797) (xy 433.324 -153.797) (xy 433.324 -153.289)
				)
			)
		)
		(zone
			(layer "B.Cu")
			(hatch none 0.5)
			(connect_pads
				(clearance 0)
			)
			(min_thickness 0.25)
			(keepout
				(tracks allowed)
				(vias not_allowed)
				(pads allowed)
				(copperpour not_allowed)
				(footprints allowed)
			)
			(placement
				(enabled no)
				(sheetname "")
			)
			(fill
				(thermal_gap 0.5)
				(thermal_bridge_width 0.5)
				(island_removal_mode 0)
			)
			(polygon
				(pts
					(xy 433.324 -153.289) (xy 433.324 -153.797) (xy 432.943 -153.797) (xy 432.943 -153.289)
				)
			)
		)
	)
)
